(kicad_pcb
	(version 20260206)
	(generator "pcbnew")
	(generator_version "10.0")
	(general
		(thickness 1.6)
		(legacy_teardrops no)
	)
	(paper "A4")
	(title_block
		(title "03242023_DA0F0TMBIJ0_F0T_Motherboard_J_brd_V01_OCP.brd")
		(comment 1 "Grand Teton / footprints 3599-3604 of 6105")
	)
	(layers
		(0 "F.Cu" signal "TOP")
		(4 "In1.Cu" signal "GND")
		(6 "In2.Cu" signal "IN1")
		(8 "In3.Cu" signal "GND1")
		(10 "In4.Cu" signal "IN2")
		(12 "In5.Cu" signal "GND2")
		(14 "In6.Cu" signal "IN3")
		(16 "In7.Cu" signal "GND3")
		(18 "In8.Cu" signal "VCC")
		(20 "In9.Cu" signal "VCC1")
		(22 "In10.Cu" signal "GND4")
		(24 "In11.Cu" signal "IN4")
		(26 "In12.Cu" signal "GND5")
		(28 "In13.Cu" signal "IN5")
		(30 "In14.Cu" signal "GND6")
		(32 "In15.Cu" signal "IN6")
		(34 "In16.Cu" signal "GND7")
		(2 "B.Cu" signal "BOTTOM")
		(9 "F.Adhes" user "F.Adhesive")
		(11 "B.Adhes" user "B.Adhesive")
		(13 "F.Paste" user "Package Geometry/Pastemask Top")
		(15 "B.Paste" user "Package Geometry/Pastemask Bottom")
		(5 "F.SilkS" user "Ref Des/Silkscreen Top")
		(7 "B.SilkS" user "Ref Des/Silkscreen Bottom")
		(1 "F.Mask" user "Board Geometry/Soldermask Top")
		(3 "B.Mask" user "Board Geometry/Soldermask Bottom")
		(17 "Dwgs.User" user "User.Drawings")
		(19 "Cmts.User" user "User.Comments")
		(21 "Eco1.User" user "User.Eco1")
		(23 "Eco2.User" user "User.Eco2")
		(25 "Edge.Cuts" user "Board Geometry/Outline")
		(27 "Margin" user)
		(31 "F.CrtYd" user "Package Geometry/Place Bound Top")
		(29 "B.CrtYd" user "Package Geometry/Place Bound Bottom")
		(35 "F.Fab" user "Ref Des/Assembly Top")
		(33 "B.Fab" user "Ref Des/Assembly Bottom")
	)
	(footprint ""
		(layer "F.Cu")
		(at 209.172556 -34.772092 90)
		(property "Reference" "U265"
			(at 3.273806 -3.826256 0)
			(unlocked yes)
			(layer "F.SilkS")
			(effects
				(font
					(size 0.7874 0.5842)
					(thickness 0.1524)
				)
			)
		)
		(property "Value" ""
			(at 0 0 90)
			(layer "F.Fab")
			(effects
				(font
					(size 1.27 1.27)
				)
			)
		)
		(duplicate_pad_numbers_are_jumpers no)
		(fp_line
			(start 1.500124 -1.500124)
			(end 1.500124 -1.004062)
			(stroke
				(width 0.1524)
				(type default)
			)
			(layer "F.SilkS")
		)
		(fp_line
			(start 1.004062 -1.500124)
			(end 1.500124 -1.500124)
			(stroke
				(width 0.1524)
				(type default)
			)
			(layer "F.SilkS")
		)
		(fp_line
			(start -1.500124 -1.500124)
			(end -1.004062 -1.500124)
			(stroke
				(width 0.1524)
				(type default)
			)
			(layer "F.SilkS")
		)
		(fp_line
			(start -1.500124 -1.004062)
			(end -1.500124 -1.500124)
			(stroke
				(width 0.1524)
				(type default)
			)
			(layer "F.SilkS")
		)
		(fp_line
			(start 1.500124 1.004062)
			(end 1.500124 1.500124)
			(stroke
				(width 0.1524)
				(type default)
			)
			(layer "F.SilkS")
		)
		(fp_line
			(start 1.500124 1.500124)
			(end 1.004062 1.500124)
			(stroke
				(width 0.1524)
				(type default)
			)
			(layer "F.SilkS")
		)
		(fp_line
			(start -1.004062 1.500124)
			(end -1.500124 1.500124)
			(stroke
				(width 0.1524)
				(type default)
			)
			(layer "F.SilkS")
		)
		(fp_line
			(start -1.500124 1.500124)
			(end -1.500124 1.004062)
			(stroke
				(width 0.1524)
				(type default)
			)
			(layer "F.SilkS")
		)
		(fp_poly
			(pts
				(xy -2.15011 -2.265934) (xy -1.790954 -1.188212) (xy -2.868422 -1.547368)
			)
			(stroke
				(width 0)
				(type default)
			)
			(fill yes)
			(layer "F.SilkS")
		)
		(fp_line
			(start 1.500124 -1.500124)
			(end 1.500124 1.500124)
			(stroke
				(width 0.1)
				(type default)
			)
			(layer "F.Fab")
		)
		(fp_line
			(start -1.500124 -1.500124)
			(end 1.500124 -1.500124)
			(stroke
				(width 0.1)
				(type default)
			)
			(layer "F.Fab")
		)
		(fp_line
			(start 1.500124 1.500124)
			(end -1.500124 1.500124)
			(stroke
				(width 0.1)
				(type default)
			)
			(layer "F.Fab")
		)
		(fp_line
			(start -1.500124 1.500124)
			(end -1.500124 -1.500124)
			(stroke
				(width 0.1)
				(type default)
			)
			(layer "F.Fab")
		)
		(fp_poly
			(pts
				(xy -2.847848 -1.258062) (xy -2.847848 -0.242062) (xy -1.831848 -0.750062)
			)
			(stroke
				(width 0)
				(type default)
			)
			(fill yes)
			(layer "F.Fab")
		)
		(pad "1" smd rect
			(at -1.400048 -0.750062)
			(size 0.2286 0.6096)
			(layers "F.Cu" "F.Mask" "F.Paste")
			(net "INA230_5_A1")
		)
		(pad "2" smd rect
			(at -1.400048 -0.249936)
			(size 0.2286 0.6096)
			(layers "F.Cu" "F.Mask" "F.Paste")
			(net "INA230_5_A0")
		)
		(pad "3" smd rect
			(at -1.400048 0.249936)
			(size 0.2286 0.6096)
			(layers "F.Cu" "F.Mask" "F.Paste")
			(net "P12V_SCM_ADC_ALERT_R")
		)
		(pad "4" smd rect
			(at -1.400048 0.750062)
			(size 0.2286 0.6096)
			(layers "F.Cu" "F.Mask" "F.Paste")
			(net "SMB_INA230_5_3V3AUX_SDA_R1")
		)
		(pad "5" smd rect
			(at -0.750062 1.400048 90)
			(size 0.2286 0.6096)
			(layers "F.Cu" "F.Mask" "F.Paste")
			(net "SMB_INA230_5_3V3AUX_SCL_R1")
		)
		(pad "6" smd rect
			(at -0.249936 1.400048 90)
			(size 0.2286 0.6096)
			(layers "F.Cu" "F.Mask" "F.Paste")
			(net "NC_INA230_5_NC0")
		)
		(pad "7" smd rect
			(at 0.249936 1.400048 90)
			(size 0.2286 0.6096)
			(layers "F.Cu" "F.Mask" "F.Paste")
			(net "NC_INA230_5_NC1")
		)
		(pad "8" smd rect
			(at 0.750062 1.400048 90)
			(size 0.2286 0.6096)
			(layers "F.Cu" "F.Mask" "F.Paste")
			(net "NC_INA230_5_NC2")
		)
		(pad "9" smd rect
			(at 1.400048 0.750062)
			(size 0.2286 0.6096)
			(layers "F.Cu" "F.Mask" "F.Paste")
			(net "P3V3_AUX")
		)
		(pad "10" smd rect
			(at 1.400048 0.249936)
			(size 0.2286 0.6096)
			(layers "F.Cu" "F.Mask" "F.Paste")
			(net "GND")
		)
		(pad "11" smd rect
			(at 1.400048 -0.249936)
			(size 0.2286 0.6096)
			(layers "F.Cu" "F.Mask" "F.Paste")
			(net "P12V_SCM_R")
		)
		(pad "12" smd rect
			(at 1.400048 -0.750062)
			(size 0.2286 0.6096)
			(layers "F.Cu" "F.Mask" "F.Paste")
			(net "VSENSE_P12V_INA230_5_INN")
		)
		(pad "13" smd rect
			(at 0.750062 -1.400048 90)
			(size 0.2286 0.6096)
			(layers "F.Cu" "F.Mask" "F.Paste")
			(net "VSENSE_P12V_INA230_5_INP")
		)
		(pad "14" smd rect
			(at 0.249936 -1.400048 90)
			(size 0.2286 0.6096)
			(layers "F.Cu" "F.Mask" "F.Paste")
			(net "NC_INA230_5_NC3")
		)
		(pad "15" smd rect
			(at -0.249936 -1.400048 90)
			(size 0.2286 0.6096)
			(layers "F.Cu" "F.Mask" "F.Paste")
			(net "NC_INA230_5_NC4")
		)
		(pad "16" smd rect
			(at -0.750062 -1.400048 90)
			(size 0.2286 0.6096)
			(layers "F.Cu" "F.Mask" "F.Paste")
			(net "NC_INA230_5_NC5")
		)
		(pad "TH" smd rect
			(at 0 0 90)
			(size 1.7018 1.7018)
			(layers "F.Cu" "F.Mask" "F.Paste")
			(net "GND")
		)
		(zone
			(layer "F.Cu")
			(hatch none 0.5)
			(connect_pads
				(clearance 0)
			)
			(min_thickness 0.25)
			(keepout
				(tracks not_allowed)
				(vias allowed)
				(pads allowed)
				(copperpour not_allowed)
				(footprints allowed)
			)
			(placement
				(enabled no)
				(sheetname "")
			)
			(fill
				(thermal_gap 0.5)
				(thermal_bridge_width 0.5)
				(island_removal_mode 0)
			)
			(polygon
				(pts
					(xy 209.147156 -33.727644) (xy 208.128108 -33.727644) (xy 208.128108 -35.81654) (xy 210.217004 -35.81654)
					(xy 210.217004 -33.727644) (xy 209.172556 -33.727644) (xy 209.172556 -33.870392) (xy 210.074256 -33.870392)
					(xy 210.074256 -35.673792) (xy 208.270856 -35.673792) (xy 208.270856 -33.870392) (xy 209.147156 -33.870392)
				)
			)
		)
	)
	(footprint ""
		(layer "F.Cu")
		(at 144.6022 -104.116378 90)
		(property "Reference" "R4055"
			(at 0 0 90)
			(layer "F.SilkS")
			(hide yes)
			(effects
				(font
					(size 1.27 1.27)
				)
			)
		)
		(property "Value" ""
			(at 0 0 90)
			(layer "F.Fab")
			(effects
				(font
					(size 1.27 1.27)
				)
			)
		)
		(duplicate_pad_numbers_are_jumpers no)
		(fp_line
			(start 0.7874 -0.4064)
			(end 0.7874 0.4064)
			(stroke
				(width 0.1524)
				(type default)
			)
			(layer "F.SilkS")
		)
		(fp_line
			(start -0.7874 -0.4064)
			(end 0.7874 -0.4064)
			(stroke
				(width 0.1524)
				(type default)
			)
			(layer "F.SilkS")
		)
		(fp_line
			(start 0.7874 0.4064)
			(end -0.7874 0.4064)
			(stroke
				(width 0.1524)
				(type default)
			)
			(layer "F.SilkS")
		)
		(fp_line
			(start -0.7874 0.4064)
			(end -0.7874 -0.4064)
			(stroke
				(width 0.1524)
				(type default)
			)
			(layer "F.SilkS")
		)
		(fp_line
			(start -0.12065 -0.305054)
			(end -0.12065 -0.2794)
			(stroke
				(width 0.1)
				(type default)
			)
			(layer "F.Fab")
		)
		(fp_line
			(start -0.67945 -0.305054)
			(end -0.12065 -0.305054)
			(stroke
				(width 0.1)
				(type default)
			)
			(layer "F.Fab")
		)
		(fp_line
			(start 0.67945 -0.3048)
			(end 0.67945 0.3048)
			(stroke
				(width 0.1)
				(type default)
			)
			(layer "F.Fab")
		)
		(fp_line
			(start 0.12065 -0.3048)
			(end 0.67945 -0.3048)
			(stroke
				(width 0.1)
				(type default)
			)
			(layer "F.Fab")
		)
		(fp_line
			(start 0.12065 -0.2794)
			(end 0.12065 -0.3048)
			(stroke
				(width 0.1)
				(type default)
			)
			(layer "F.Fab")
		)
		(fp_line
			(start -0.12065 -0.2794)
			(end 0.12065 -0.2794)
			(stroke
				(width 0.1)
				(type default)
			)
			(layer "F.Fab")
		)
		(fp_line
			(start 0.120396 0.2794)
			(end -0.12065 0.2794)
			(stroke
				(width 0.1)
				(type default)
			)
			(layer "F.Fab")
		)
		(fp_line
			(start -0.12065 0.2794)
			(end -0.12065 0.3048)
			(stroke
				(width 0.1)
				(type default)
			)
			(layer "F.Fab")
		)
		(fp_line
			(start 0.67945 0.3048)
			(end 0.120396 0.3048)
			(stroke
				(width 0.1)
				(type default)
			)
			(layer "F.Fab")
		)
		(fp_line
			(start 0.120396 0.3048)
			(end 0.120396 0.2794)
			(stroke
				(width 0.1)
				(type default)
			)
			(layer "F.Fab")
		)
		(fp_line
			(start -0.12065 0.3048)
			(end -0.67945 0.3048)
			(stroke
				(width 0.1)
				(type default)
			)
			(layer "F.Fab")
		)
		(fp_line
			(start -0.67945 0.3048)
			(end -0.67945 -0.305054)
			(stroke
				(width 0.1)
				(type default)
			)
			(layer "F.Fab")
		)
		(pad "1" smd circle
			(at -0.40005 0 90)
			(size 0 0)
			(layers "F.Cu" "F.Mask" "F.Paste")
			(net "PD_CPU1_ERRS_U306_DIR")
		)
		(pad "2" smd circle
			(at 0.40005 0 90)
			(size 0 0)
			(layers "F.Cu" "F.Mask" "F.Paste")
			(net "GND")
		)
	)
	(footprint ""
		(layer "F.Cu")
		(at 34.291524 -124.99721 90)
		(property "Reference" "R4594"
			(at 0 0 90)
			(layer "F.SilkS")
			(hide yes)
			(effects
				(font
					(size 1.27 1.27)
				)
			)
		)
		(property "Value" ""
			(at 0 0 90)
			(layer "F.Fab")
			(effects
				(font
					(size 1.27 1.27)
				)
			)
		)
		(duplicate_pad_numbers_are_jumpers no)
		(fp_line
			(start 0.7874 -0.4064)
			(end 0.7874 0.4064)
			(stroke
				(width 0.1524)
				(type default)
			)
			(layer "F.SilkS")
		)
		(fp_line
			(start -0.7874 -0.4064)
			(end 0.7874 -0.4064)
			(stroke
				(width 0.1524)
				(type default)
			)
			(layer "F.SilkS")
		)
		(fp_line
			(start 0.7874 0.4064)
			(end -0.7874 0.4064)
			(stroke
				(width 0.1524)
				(type default)
			)
			(layer "F.SilkS")
		)
		(fp_line
			(start -0.7874 0.4064)
			(end -0.7874 -0.4064)
			(stroke
				(width 0.1524)
				(type default)
			)
			(layer "F.SilkS")
		)
		(fp_line
			(start -0.12065 -0.305054)
			(end -0.12065 -0.2794)
			(stroke
				(width 0.1)
				(type default)
			)
			(layer "F.Fab")
		)
		(fp_line
			(start -0.67945 -0.305054)
			(end -0.12065 -0.305054)
			(stroke
				(width 0.1)
				(type default)
			)
			(layer "F.Fab")
		)
		(fp_line
			(start 0.67945 -0.3048)
			(end 0.67945 0.3048)
			(stroke
				(width 0.1)
				(type default)
			)
			(layer "F.Fab")
		)
		(fp_line
			(start 0.12065 -0.3048)
			(end 0.67945 -0.3048)
			(stroke
				(width 0.1)
				(type default)
			)
			(layer "F.Fab")
		)
		(fp_line
			(start 0.12065 -0.2794)
			(end 0.12065 -0.3048)
			(stroke
				(width 0.1)
				(type default)
			)
			(layer "F.Fab")
		)
		(fp_line
			(start -0.12065 -0.2794)
			(end 0.12065 -0.2794)
			(stroke
				(width 0.1)
				(type default)
			)
			(layer "F.Fab")
		)
		(fp_line
			(start 0.120396 0.2794)
			(end -0.12065 0.2794)
			(stroke
				(width 0.1)
				(type default)
			)
			(layer "F.Fab")
		)
		(fp_line
			(start -0.12065 0.2794)
			(end -0.12065 0.3048)
			(stroke
				(width 0.1)
				(type default)
			)
			(layer "F.Fab")
		)
		(fp_line
			(start 0.67945 0.3048)
			(end 0.120396 0.3048)
			(stroke
				(width 0.1)
				(type default)
			)
			(layer "F.Fab")
		)
		(fp_line
			(start 0.120396 0.3048)
			(end 0.120396 0.2794)
			(stroke
				(width 0.1)
				(type default)
			)
			(layer "F.Fab")
		)
		(fp_line
			(start -0.12065 0.3048)
			(end -0.67945 0.3048)
			(stroke
				(width 0.1)
				(type default)
			)
			(layer "F.Fab")
		)
		(fp_line
			(start -0.67945 0.3048)
			(end -0.67945 -0.305054)
			(stroke
				(width 0.1)
				(type default)
			)
			(layer "F.Fab")
		)
		(pad "1" smd circle
			(at -0.40005 0 90)
			(size 0 0)
			(layers "F.Cu" "F.Mask" "F.Paste")
			(net "SMB_VR_3V3AUX_SCL_R")
		)
		(pad "2" smd circle
			(at 0.40005 0 90)
			(size 0 0)
			(layers "F.Cu" "F.Mask" "F.Paste")
			(net "SMB_CLK_PVCCINFAON_CPU1")
		)
	)
	(footprint ""
		(layer "F.Cu")
		(at 309.522622 -44.948348 180)
		(property "Reference" "R607"
			(at 0 0 180)
			(layer "F.SilkS")
			(hide yes)
			(effects
				(font
					(size 1.27 1.27)
				)
			)
		)
		(property "Value" ""
			(at 0 0 180)
			(layer "F.Fab")
			(effects
				(font
					(size 1.27 1.27)
				)
			)
		)
		(duplicate_pad_numbers_are_jumpers no)
		(fp_line
			(start 0.7874 0.4064)
			(end -0.7874 0.4064)
			(stroke
				(width 0.1524)
				(type default)
			)
			(layer "F.SilkS")
		)
		(fp_line
			(start 0.7874 -0.4064)
			(end 0.7874 0.4064)
			(stroke
				(width 0.1524)
				(type default)
			)
			(layer "F.SilkS")
		)
		(fp_line
			(start -0.7874 0.4064)
			(end -0.7874 -0.4064)
			(stroke
				(width 0.1524)
				(type default)
			)
			(layer "F.SilkS")
		)
		(fp_line
			(start -0.7874 -0.4064)
			(end 0.7874 -0.4064)
			(stroke
				(width 0.1524)
				(type default)
			)
			(layer "F.SilkS")
		)
		(fp_line
			(start 0.67945 0.3048)
			(end 0.120396 0.3048)
			(stroke
				(width 0.1)
				(type default)
			)
			(layer "F.Fab")
		)
		(fp_line
			(start 0.67945 -0.3048)
			(end 0.67945 0.3048)
			(stroke
				(width 0.1)
				(type default)
			)
			(layer "F.Fab")
		)
		(fp_line
			(start 0.12065 -0.2794)
			(end 0.12065 -0.3048)
			(stroke
				(width 0.1)
				(type default)
			)
			(layer "F.Fab")
		)
		(fp_line
			(start 0.12065 -0.3048)
			(end 0.67945 -0.3048)
			(stroke
				(width 0.1)
				(type default)
			)
			(layer "F.Fab")
		)
		(fp_line
			(start 0.120396 0.3048)
			(end 0.120396 0.2794)
			(stroke
				(width 0.1)
				(type default)
			)
			(layer "F.Fab")
		)
		(fp_line
			(start 0.120396 0.2794)
			(end -0.12065 0.2794)
			(stroke
				(width 0.1)
				(type default)
			)
			(layer "F.Fab")
		)
		(fp_line
			(start -0.12065 0.3048)
			(end -0.67945 0.3048)
			(stroke
				(width 0.1)
				(type default)
			)
			(layer "F.Fab")
		)
		(fp_line
			(start -0.12065 0.2794)
			(end -0.12065 0.3048)
			(stroke
				(width 0.1)
				(type default)
			)
			(layer "F.Fab")
		)
		(fp_line
			(start -0.12065 -0.2794)
			(end 0.12065 -0.2794)
			(stroke
				(width 0.1)
				(type default)
			)
			(layer "F.Fab")
		)
		(fp_line
			(start -0.12065 -0.305054)
			(end -0.12065 -0.2794)
			(stroke
				(width 0.1)
				(type default)
			)
			(layer "F.Fab")
		)
		(fp_line
			(start -0.67945 0.3048)
			(end -0.67945 -0.305054)
			(stroke
				(width 0.1)
				(type default)
			)
			(layer "F.Fab")
		)
		(fp_line
			(start -0.67945 -0.305054)
			(end -0.12065 -0.305054)
			(stroke
				(width 0.1)
				(type default)
			)
			(layer "F.Fab")
		)
		(pad "1" smd circle
			(at -0.40005 0 180)
			(size 0 0)
			(layers "F.Cu" "F.Mask" "F.Paste")
			(net "P3V3_AUX")
		)
		(pad "2" smd circle
			(at 0.40005 0 180)
			(size 0 0)
			(layers "F.Cu" "F.Mask" "F.Paste")
			(net "FM_ESPI_FLASH_MODE")
		)
	)
	(footprint ""
		(layer "F.Cu")
		(at 368.72164 -403.936708 180)
		(property "Reference" "R4173"
			(at 0 0 180)
			(layer "F.SilkS")
			(hide yes)
			(effects
				(font
					(size 1.27 1.27)
				)
			)
		)
		(property "Value" ""
			(at 0 0 180)
			(layer "F.Fab")
			(effects
				(font
					(size 1.27 1.27)
				)
			)
		)
		(duplicate_pad_numbers_are_jumpers no)
		(fp_line
			(start 0.7874 0.4064)
			(end -0.7874 0.4064)
			(stroke
				(width 0.1524)
				(type default)
			)
			(layer "F.SilkS")
		)
		(fp_line
			(start 0.7874 -0.4064)
			(end 0.7874 0.4064)
			(stroke
				(width 0.1524)
				(type default)
			)
			(layer "F.SilkS")
		)
		(fp_line
			(start -0.7874 0.4064)
			(end -0.7874 -0.4064)
			(stroke
				(width 0.1524)
				(type default)
			)
			(layer "F.SilkS")
		)
		(fp_line
			(start -0.7874 -0.4064)
			(end 0.7874 -0.4064)
			(stroke
				(width 0.1524)
				(type default)
			)
			(layer "F.SilkS")
		)
		(fp_line
			(start 0.67945 0.3048)
			(end 0.120396 0.3048)
			(stroke
				(width 0.1)
				(type default)
			)
			(layer "F.Fab")
		)
		(fp_line
			(start 0.67945 -0.3048)
			(end 0.67945 0.3048)
			(stroke
				(width 0.1)
				(type default)
			)
			(layer "F.Fab")
		)
		(fp_line
			(start 0.12065 -0.2794)
			(end 0.12065 -0.3048)
			(stroke
				(width 0.1)
				(type default)
			)
			(layer "F.Fab")
		)
		(fp_line
			(start 0.12065 -0.3048)
			(end 0.67945 -0.3048)
			(stroke
				(width 0.1)
				(type default)
			)
			(layer "F.Fab")
		)
		(fp_line
			(start 0.120396 0.3048)
			(end 0.120396 0.2794)
			(stroke
				(width 0.1)
				(type default)
			)
			(layer "F.Fab")
		)
		(fp_line
			(start 0.120396 0.2794)
			(end -0.12065 0.2794)
			(stroke
				(width 0.1)
				(type default)
			)
			(layer "F.Fab")
		)
		(fp_line
			(start -0.12065 0.3048)
			(end -0.67945 0.3048)
			(stroke
				(width 0.1)
				(type default)
			)
			(layer "F.Fab")
		)
		(fp_line
			(start -0.12065 0.2794)
			(end -0.12065 0.3048)
			(stroke
				(width 0.1)
				(type default)
			)
			(layer "F.Fab")
		)
		(fp_line
			(start -0.12065 -0.2794)
			(end 0.12065 -0.2794)
			(stroke
				(width 0.1)
				(type default)
			)
			(layer "F.Fab")
		)
		(fp_line
			(start -0.12065 -0.305054)
			(end -0.12065 -0.2794)
			(stroke
				(width 0.1)
				(type default)
			)
			(layer "F.Fab")
		)
		(fp_line
			(start -0.67945 0.3048)
			(end -0.67945 -0.305054)
			(stroke
				(width 0.1)
				(type default)
			)
			(layer "F.Fab")
		)
		(fp_line
			(start -0.67945 -0.305054)
			(end -0.12065 -0.305054)
			(stroke
				(width 0.1)
				(type default)
			)
			(layer "F.Fab")
		)
		(pad "1" smd circle
			(at -0.40005 0 180)
			(size 0 0)
			(layers "F.Cu" "F.Mask" "F.Paste")
			(net "P3V3_AUX")
		)
		(pad "2" smd circle
			(at 0.40005 0 180)
			(size 0 0)
			(layers "F.Cu" "F.Mask" "F.Paste")
			(net "UART_BMC_BIC_R_BUF_RX")
		)
	)
	(footprint ""
		(layer "F.Cu")
		(at 121.043954 -402.371052 -90)
		(property "Reference" "C742"
			(at 0 0 270)
			(layer "F.SilkS")
			(hide yes)
			(effects
				(font
					(size 1.27 1.27)
				)
			)
		)
		(property "Value" ""
			(at 0 0 270)
			(layer "F.Fab")
			(effects
				(font
					(size 1.27 1.27)
				)
			)
		)
		(duplicate_pad_numbers_are_jumpers no)
		(fp_line
			(start -0.299974 0.150114)
			(end -0.299974 -0.150114)
			(stroke
				(width 0.1)
				(type default)
			)
			(layer "F.Fab")
		)
		(fp_line
			(start 0.299974 0.150114)
			(end -0.299974 0.150114)
			(stroke
				(width 0.1)
				(type default)
			)
			(layer "F.Fab")
		)
		(fp_line
			(start -0.299974 -0.150114)
			(end 0.299974 -0.150114)
			(stroke
				(width 0.1)
				(type default)
			)
			(layer "F.Fab")
		)
		(fp_line
			(start 0.299974 -0.150114)
			(end 0.299974 0.150114)
			(stroke
				(width 0.1)
				(type default)
			)
			(layer "F.Fab")
		)
		(pad "1" smd rect
			(at -0.2667 0 270)
			(size 0.3048 0.381)
			(layers "F.Cu" "F.Mask" "F.Paste")
			(net "P5E_CPU1_PE2_TX_C_DN<15>")
		)
		(pad "2" smd rect
			(at 0.2667 0 270)
			(size 0.3048 0.381)
			(layers "F.Cu" "F.Mask" "F.Paste")
			(net "P5E_CPU1_PE2_TX_DN<15>")
		)
	)
)
